(kicad_pcb
	(version 20260206)
	(generator "pcbnew")
	(generator_version "10.0")
	(general
		(thickness 1.6)
		(legacy_teardrops no)
	)
	(paper "A4")
	(title_block
		(title "dpb — 14545-sa.0730WZS0815.brd")
		(comment 1 "Honey Badger (Wiwynn) / footprints 621-627 of 1066")
	)
	(layers
		(0 "F.Cu" signal "TOP")
		(4 "In1.Cu" signal "L2GND")
		(6 "In2.Cu" signal "L3")
		(8 "In3.Cu" signal "L4VCC")
		(10 "In4.Cu" signal "L5VCC")
		(12 "In5.Cu" signal "L6")
		(14 "In6.Cu" signal "L7GND")
		(2 "B.Cu" signal "BOTTOM")
		(9 "F.Adhes" user "F.Adhesive")
		(11 "B.Adhes" user "B.Adhesive")
		(13 "F.Paste" user "Package Geometry/Pastemask Top")
		(15 "B.Paste" user "Package Geometry/Pastemask Bottom")
		(5 "F.SilkS" user "Ref Des/Silkscreen Top")
		(7 "B.SilkS" user "Ref Des/Silkscreen Bottom")
		(1 "F.Mask" user "Board Geometry/Soldermask Top")
		(3 "B.Mask" user "Board Geometry/Soldermask Bottom")
		(17 "Dwgs.User" user "User.Drawings")
		(19 "Cmts.User" user "User.Comments")
		(21 "Eco1.User" user "User.Eco1")
		(23 "Eco2.User" user "User.Eco2")
		(25 "Edge.Cuts" user "Board Geometry/Outline")
		(27 "Margin" user)
		(31 "F.CrtYd" user "Package Geometry/Place Bound Top")
		(29 "B.CrtYd" user "Package Geometry/Place Bound Bottom")
		(35 "F.Fab" user "Ref Des/Assembly Top")
		(33 "B.Fab" user "Ref Des/Assembly Bottom")
	)
	(footprint ""
		(layer "F.Cu")
		(at 16.662146 -470.3826 90)
		(property "Reference" "R500"
			(at 0 0 90)
			(layer "F.SilkS")
			(hide yes)
			(effects
				(font
					(size 1.27 1.27)
				)
			)
		)
		(property "Value" "1KR2F-3-GP"
			(at 0.064008 -3.993896 90)
			(unlocked yes)
			(layer "F.Fab")
			(hide yes)
			(effects
				(font
					(size 1.016 1.016)
					(thickness 0.1524)
				)
			)
		)
		(property "Device Type" "R402H16"
			(at 0.064008 -5.517896 90)
			(unlocked yes)
			(layer "F.Fab")
			(hide yes)
			(effects
				(font
					(size 1.016 1.016)
					(thickness 0.1524)
				)
			)
		)
		(duplicate_pad_numbers_are_jumpers no)
		(fp_line
			(start 0.508 -0.9398)
			(end -0.508 -0.9398)
			(stroke
				(width 0.1524)
				(type default)
			)
			(layer "F.SilkS")
		)
		(fp_line
			(start -0.508 -0.9398)
			(end -0.508 0.9398)
			(stroke
				(width 0.1524)
				(type default)
			)
			(layer "F.SilkS")
		)
		(fp_rect
			(start -0.508 0.9398)
			(end 0.508 -0.9398)
			(stroke
				(width 0)
				(type default)
			)
			(fill no)
			(layer "F.CrtYd")
		)
		(fp_rect
			(start -0.508 0.9398)
			(end 0.508 -0.9398)
			(stroke
				(width 0)
				(type default)
			)
			(fill no)
			(layer "F.Fab")
		)
		(pad "1" smd custom
			(at 0 -0.4445 90)
			(size 0.1397 0.1397)
			(layers "F.Cu" "F.Mask" "F.Paste")
			(net "FLT_HDD10_B")
			(options
				(clearance outline)
				(anchor circle)
			)
			(primitives
				(gr_poly
					(pts
						(arc
							(start -0.1778 -0.2794)
							(mid -0.249642 -0.249642)
							(end -0.2794 -0.1778)
						)
						(arc
							(start -0.2794 0.1778)
							(mid -0.249642 0.249642)
							(end -0.1778 0.2794)
						)
						(arc
							(start 0.1778 0.2794)
							(mid 0.249642 0.249642)
							(end 0.2794 0.1778)
						)
						(arc
							(start 0.2794 -0.1778)
							(mid 0.249642 -0.249642)
							(end 0.1778 -0.2794)
						)
					)
					(width 0)
					(fill yes)
				)
			)
		)
		(pad "2" smd custom
			(at 0 0.4445 90)
			(size 0.1397 0.1397)
			(layers "F.Cu" "F.Mask" "F.Paste")
			(net "FLT_HDD10_DRIVE")
			(options
				(clearance outline)
				(anchor circle)
			)
			(primitives
				(gr_poly
					(pts
						(arc
							(start -0.1778 -0.2794)
							(mid -0.249642 -0.249642)
							(end -0.2794 -0.1778)
						)
						(arc
							(start -0.2794 0.1778)
							(mid -0.249642 0.249642)
							(end -0.1778 0.2794)
						)
						(arc
							(start 0.1778 0.2794)
							(mid 0.249642 0.249642)
							(end 0.2794 0.1778)
						)
						(arc
							(start 0.2794 -0.1778)
							(mid 0.249642 -0.249642)
							(end 0.1778 -0.2794)
						)
					)
					(width 0)
					(fill yes)
				)
			)
		)
	)
	(footprint ""
		(layer "F.Cu")
		(at 217.473784 -188.488828 180)
		(property "Reference" "C162"
			(at 0 0 180)
			(layer "F.SilkS")
			(hide yes)
			(effects
				(font
					(size 1.27 1.27)
				)
			)
		)
		(property "Value" "SC10U25V6KX-1GP"
			(at -0.0762 -5.1308 180)
			(unlocked yes)
			(layer "F.Fab")
			(hide yes)
			(effects
				(font
					(size 1.016 1.016)
					(thickness 0.1524)
				)
			)
		)
		(property "Device Type" "C1206H71"
			(at -0.127 -6.6548 180)
			(unlocked yes)
			(layer "F.Fab")
			(hide yes)
			(effects
				(font
					(size 1.016 1.016)
					(thickness 0.1524)
				)
			)
		)
		(duplicate_pad_numbers_are_jumpers no)
		(fp_line
			(start 1.016 2.2352)
			(end -1.016 2.2352)
			(stroke
				(width 0.1524)
				(type default)
			)
			(layer "F.SilkS")
		)
		(fp_line
			(start 1.016 0.8382)
			(end 1.016 2.2352)
			(stroke
				(width 0.1524)
				(type default)
			)
			(layer "F.SilkS")
		)
		(fp_line
			(start 1.016 -2.2352)
			(end 1.016 -0.8382)
			(stroke
				(width 0.1524)
				(type default)
			)
			(layer "F.SilkS")
		)
		(fp_line
			(start -1.016 2.2352)
			(end -1.016 0.8382)
			(stroke
				(width 0.1524)
				(type default)
			)
			(layer "F.SilkS")
		)
		(fp_line
			(start -1.016 -0.8382)
			(end -1.016 -2.2352)
			(stroke
				(width 0.1524)
				(type default)
			)
			(layer "F.SilkS")
		)
		(fp_line
			(start -1.016 -2.2352)
			(end 1.016 -2.2352)
			(stroke
				(width 0.1524)
				(type default)
			)
			(layer "F.SilkS")
		)
		(fp_rect
			(start -1.0922 2.3114)
			(end 1.0922 -2.3114)
			(stroke
				(width 0)
				(type default)
			)
			(fill no)
			(layer "F.CrtYd")
		)
		(fp_poly
			(pts
				(xy 1.0922 -2.3114) (xy 1.0922 2.3114) (xy -1.0922 2.3114) (xy -1.0922 -2.3114)
			)
			(stroke
				(width 0)
				(type default)
			)
			(fill no)
			(layer "F.Fab")
		)
		(pad "1" smd rect
			(at 0 -1.397 180)
			(size 1.651 1.27)
			(layers "F.Cu" "F.Mask" "F.Paste")
			(net "P12V_HDD3")
		)
		(pad "2" smd rect
			(at 0 1.397 180)
			(size 1.651 1.27)
			(layers "F.Cu" "F.Mask" "F.Paste")
			(net "GND")
		)
	)
	(footprint ""
		(layer "F.Cu")
		(at 32.0802 -335.2546 90)
		(property "Reference" "R398"
			(at 0 0 90)
			(layer "F.SilkS")
			(hide yes)
			(effects
				(font
					(size 1.27 1.27)
				)
			)
		)
		(property "Value" "0R2J-2-GP"
			(at 0.064008 -3.993896 90)
			(unlocked yes)
			(layer "F.Fab")
			(hide yes)
			(effects
				(font
					(size 1.016 1.016)
					(thickness 0.1524)
				)
			)
		)
		(property "Device Type" "R402H16"
			(at 0.064008 -5.517896 90)
			(unlocked yes)
			(layer "F.Fab")
			(hide yes)
			(effects
				(font
					(size 1.016 1.016)
					(thickness 0.1524)
				)
			)
		)
		(duplicate_pad_numbers_are_jumpers no)
		(fp_line
			(start 0.508 -0.9398)
			(end -0.508 -0.9398)
			(stroke
				(width 0.1524)
				(type default)
			)
			(layer "F.SilkS")
		)
		(fp_line
			(start -0.508 -0.9398)
			(end -0.508 0.9398)
			(stroke
				(width 0.1524)
				(type default)
			)
			(layer "F.SilkS")
		)
		(fp_rect
			(start -0.508 0.9398)
			(end 0.508 -0.9398)
			(stroke
				(width 0)
				(type default)
			)
			(fill no)
			(layer "F.CrtYd")
		)
		(fp_rect
			(start -0.508 0.9398)
			(end 0.508 -0.9398)
			(stroke
				(width 0)
				(type default)
			)
			(fill no)
			(layer "F.Fab")
		)
		(pad "1" smd custom
			(at 0 -0.4445 90)
			(size 0.1397 0.1397)
			(layers "F.Cu" "F.Mask" "F.Paste")
			(net "HDD_PRSNT_NET11")
			(options
				(clearance outline)
				(anchor circle)
			)
			(primitives
				(gr_poly
					(pts
						(arc
							(start -0.1778 -0.2794)
							(mid -0.249642 -0.249642)
							(end -0.2794 -0.1778)
						)
						(arc
							(start -0.2794 0.1778)
							(mid -0.249642 0.249642)
							(end -0.1778 0.2794)
						)
						(arc
							(start 0.1778 0.2794)
							(mid 0.249642 0.249642)
							(end 0.2794 0.1778)
						)
						(arc
							(start 0.2794 -0.1778)
							(mid 0.249642 -0.249642)
							(end 0.1778 -0.2794)
						)
					)
					(width 0)
					(fill yes)
				)
			)
		)
		(pad "2" smd custom
			(at 0 0.4445 90)
			(size 0.1397 0.1397)
			(layers "F.Cu" "F.Mask" "F.Paste")
			(net "HDD11_LED_B")
			(options
				(clearance outline)
				(anchor circle)
			)
			(primitives
				(gr_poly
					(pts
						(arc
							(start -0.1778 -0.2794)
							(mid -0.249642 -0.249642)
							(end -0.2794 -0.1778)
						)
						(arc
							(start -0.2794 0.1778)
							(mid -0.249642 0.249642)
							(end -0.1778 0.2794)
						)
						(arc
							(start 0.1778 0.2794)
							(mid 0.249642 0.249642)
							(end 0.2794 0.1778)
						)
						(arc
							(start 0.2794 -0.1778)
							(mid 0.249642 -0.249642)
							(end 0.1778 -0.2794)
						)
					)
					(width 0)
					(fill yes)
				)
			)
		)
	)
	(footprint ""
		(layer "F.Cu")
		(at 207.8736 -67.945 -90)
		(property "Reference" "Q54"
			(at 0 0 270)
			(layer "F.SilkS")
			(hide yes)
			(effects
				(font
					(size 1.27 1.27)
				)
			)
		)
		(property "Value" "2N7002DW-7F-GP"
			(at -2.3622 -8.2042 270)
			(unlocked yes)
			(layer "F.Fab")
			(hide yes)
			(effects
				(font
					(size 1.016 1.016)
					(thickness 0.1524)
				)
			)
		)
		(property "Device Type" "SOT-363H44"
			(at -2.3622 -10.1092 270)
			(unlocked yes)
			(layer "F.Fab")
			(hide yes)
			(effects
				(font
					(size 1.016 1.016)
					(thickness 0.1524)
				)
			)
		)
		(duplicate_pad_numbers_are_jumpers no)
		(fp_line
			(start -1.4478 1.7018)
			(end 1.4478 1.7018)
			(stroke
				(width 0.1524)
				(type default)
			)
			(layer "F.SilkS")
		)
		(fp_line
			(start 1.4478 1.7018)
			(end 1.4478 -1.7018)
			(stroke
				(width 0.1524)
				(type default)
			)
			(layer "F.SilkS")
		)
		(fp_line
			(start -1.27 1.524)
			(end -1.27 0.6604)
			(stroke
				(width 0.4826)
				(type default)
			)
			(layer "F.SilkS")
		)
		(fp_line
			(start -1.4478 -1.7018)
			(end -1.4478 1.7018)
			(stroke
				(width 0.1524)
				(type default)
			)
			(layer "F.SilkS")
		)
		(fp_line
			(start 1.4478 -1.7018)
			(end -1.4478 -1.7018)
			(stroke
				(width 0.1524)
				(type default)
			)
			(layer "F.SilkS")
		)
		(fp_poly
			(pts
				(xy -1.524 -1.778) (xy 1.524 -1.778) (xy 1.524 1.778) (xy -1.524 1.778)
			)
			(stroke
				(width 0)
				(type default)
			)
			(fill no)
			(layer "F.CrtYd")
		)
		(fp_poly
			(pts
				(xy -1.524 -1.778) (xy 1.524 -1.778) (xy 1.524 1.778) (xy -1.524 1.778)
			)
			(stroke
				(width 0)
				(type default)
			)
			(fill no)
			(layer "F.Fab")
		)
		(pad "1" smd rect
			(at -0.65024 0.9398 270)
			(size 0.4064 1.016)
			(layers "F.Cu" "F.Mask" "F.Paste")
			(net "P3V3_HDD4_LED")
		)
		(pad "2" smd rect
			(at 0 0.9398 270)
			(size 0.4064 1.016)
			(layers "F.Cu" "F.Mask" "F.Paste")
			(net "HDD4_LED_G")
		)
		(pad "3" smd rect
			(at 0.65024 0.9398 270)
			(size 0.4064 1.016)
			(layers "F.Cu" "F.Mask" "F.Paste")
			(net "P5VA")
		)
		(pad "4" smd rect
			(at 0.65024 -0.9398 270)
			(size 0.4064 1.016)
			(layers "F.Cu" "F.Mask" "F.Paste")
			(net "P5VA_HDD4_LED")
		)
		(pad "5" smd rect
			(at 0 -0.9398 270)
			(size 0.4064 1.016)
			(layers "F.Cu" "F.Mask" "F.Paste")
			(net "HDD4_LED_G")
		)
		(pad "6" smd rect
			(at -0.65024 -0.9398 270)
			(size 0.4064 1.016)
			(layers "F.Cu" "F.Mask" "F.Paste")
			(net "P3V3")
		)
	)
	(footprint ""
		(layer "F.Cu")
		(at 32.892746 -314.734702)
		(property "Reference" "C288"
			(at 0 0 0)
			(layer "F.SilkS")
			(hide yes)
			(effects
				(font
					(size 1.27 1.27)
				)
			)
		)
		(property "Value" "SC10U25V6KX-1GP"
			(at -0.0762 -5.1308 0)
			(unlocked yes)
			(layer "F.Fab")
			(hide yes)
			(effects
				(font
					(size 1.016 1.016)
					(thickness 0.1524)
				)
			)
		)
		(property "Device Type" "C1206H71"
			(at -0.127 -6.6548 0)
			(unlocked yes)
			(layer "F.Fab")
			(hide yes)
			(effects
				(font
					(size 1.016 1.016)
					(thickness 0.1524)
				)
			)
		)
		(duplicate_pad_numbers_are_jumpers no)
		(fp_line
			(start -1.016 -2.2352)
			(end 1.016 -2.2352)
			(stroke
				(width 0.1524)
				(type default)
			)
			(layer "F.SilkS")
		)
		(fp_line
			(start -1.016 -0.8382)
			(end -1.016 -2.2352)
			(stroke
				(width 0.1524)
				(type default)
			)
			(layer "F.SilkS")
		)
		(fp_line
			(start -1.016 2.2352)
			(end -1.016 0.8382)
			(stroke
				(width 0.1524)
				(type default)
			)
			(layer "F.SilkS")
		)
		(fp_line
			(start 1.016 -2.2352)
			(end 1.016 -0.8382)
			(stroke
				(width 0.1524)
				(type default)
			)
			(layer "F.SilkS")
		)
		(fp_line
			(start 1.016 0.8382)
			(end 1.016 2.2352)
			(stroke
				(width 0.1524)
				(type default)
			)
			(layer "F.SilkS")
		)
		(fp_line
			(start 1.016 2.2352)
			(end -1.016 2.2352)
			(stroke
				(width 0.1524)
				(type default)
			)
			(layer "F.SilkS")
		)
		(fp_rect
			(start -1.0922 2.3114)
			(end 1.0922 -2.3114)
			(stroke
				(width 0)
				(type default)
			)
			(fill no)
			(layer "F.CrtYd")
		)
		(fp_poly
			(pts
				(xy 1.0922 -2.3114) (xy 1.0922 2.3114) (xy -1.0922 2.3114) (xy -1.0922 -2.3114)
			)
			(stroke
				(width 0)
				(type default)
			)
			(fill no)
			(layer "F.Fab")
		)
		(pad "1" smd rect
			(at 0 -1.397)
			(size 1.651 1.27)
			(layers "F.Cu" "F.Mask" "F.Paste")
			(net "P12V_HDD11")
		)
		(pad "2" smd rect
			(at 0 1.397)
			(size 1.651 1.27)
			(layers "F.Cu" "F.Mask" "F.Paste")
			(net "GND")
		)
	)
	(footprint ""
		(layer "F.Cu")
		(at 191.853058 -388.949184 -90)
		(property "Reference" "R119"
			(at 0 0 270)
			(layer "F.SilkS")
			(hide yes)
			(effects
				(font
					(size 1.27 1.27)
				)
			)
		)
		(property "Value" "1KR2F-3-GP"
			(at 0.064008 -3.993896 270)
			(unlocked yes)
			(layer "F.Fab")
			(hide yes)
			(effects
				(font
					(size 1.016 1.016)
					(thickness 0.1524)
				)
			)
		)
		(property "Device Type" "R402H16"
			(at 0.064008 -5.517896 270)
			(unlocked yes)
			(layer "F.Fab")
			(hide yes)
			(effects
				(font
					(size 1.016 1.016)
					(thickness 0.1524)
				)
			)
		)
		(duplicate_pad_numbers_are_jumpers no)
		(fp_line
			(start -0.508 -0.9398)
			(end -0.508 0.9398)
			(stroke
				(width 0.1524)
				(type default)
			)
			(layer "F.SilkS")
		)
		(fp_line
			(start 0.508 -0.9398)
			(end -0.508 -0.9398)
			(stroke
				(width 0.1524)
				(type default)
			)
			(layer "F.SilkS")
		)
		(fp_rect
			(start -0.508 0.9398)
			(end 0.508 -0.9398)
			(stroke
				(width 0)
				(type default)
			)
			(fill no)
			(layer "F.CrtYd")
		)
		(fp_rect
			(start -0.508 0.9398)
			(end 0.508 -0.9398)
			(stroke
				(width 0)
				(type default)
			)
			(fill no)
			(layer "F.Fab")
		)
		(pad "1" smd custom
			(at 0 -0.4445 270)
			(size 0.1397 0.1397)
			(layers "F.Cu" "F.Mask" "F.Paste")
			(net "P3V3")
			(options
				(clearance outline)
				(anchor circle)
			)
			(primitives
				(gr_poly
					(pts
						(arc
							(start -0.1778 -0.2794)
							(mid -0.249642 -0.249642)
							(end -0.2794 -0.1778)
						)
						(arc
							(start -0.2794 0.1778)
							(mid -0.249642 0.249642)
							(end -0.1778 0.2794)
						)
						(arc
							(start 0.1778 0.2794)
							(mid 0.249642 0.249642)
							(end 0.2794 0.1778)
						)
						(arc
							(start 0.2794 -0.1778)
							(mid 0.249642 -0.249642)
							(end 0.1778 -0.2794)
						)
					)
					(width 0)
					(fill yes)
				)
			)
		)
		(pad "2" smd custom
			(at 0 0.4445 270)
			(size 0.1397 0.1397)
			(layers "F.Cu" "F.Mask" "F.Paste")
			(net "SW_PWR_HDD1")
			(options
				(clearance outline)
				(anchor circle)
			)
			(primitives
				(gr_poly
					(pts
						(arc
							(start -0.1778 -0.2794)
							(mid -0.249642 -0.249642)
							(end -0.2794 -0.1778)
						)
						(arc
							(start -0.2794 0.1778)
							(mid -0.249642 0.249642)
							(end -0.1778 0.2794)
						)
						(arc
							(start 0.1778 0.2794)
							(mid 0.249642 0.249642)
							(end 0.2794 0.1778)
						)
						(arc
							(start 0.2794 -0.1778)
							(mid 0.249642 -0.249642)
							(end 0.1778 -0.2794)
						)
					)
					(width 0)
					(fill yes)
				)
			)
		)
	)
	(footprint ""
		(layer "F.Cu")
		(at 45.275246 -247.0277 90)
		(property "Reference" "R200"
			(at 0 0 90)
			(layer "F.SilkS")
			(hide yes)
			(effects
				(font
					(size 1.27 1.27)
				)
			)
		)
		(property "Value" "0R2J-2-GP"
			(at 0.064008 -3.993896 90)
			(unlocked yes)
			(layer "F.Fab")
			(hide yes)
			(effects
				(font
					(size 1.016 1.016)
					(thickness 0.1524)
				)
			)
		)
		(property "Device Type" "R402H16"
			(at 0.064008 -5.517896 90)
			(unlocked yes)
			(layer "F.Fab")
			(hide yes)
			(effects
				(font
					(size 1.016 1.016)
					(thickness 0.1524)
				)
			)
		)
		(duplicate_pad_numbers_are_jumpers no)
		(fp_line
			(start 0.508 -0.9398)
			(end -0.508 -0.9398)
			(stroke
				(width 0.1524)
				(type default)
			)
			(layer "F.SilkS")
		)
		(fp_line
			(start -0.508 -0.9398)
			(end -0.508 0.9398)
			(stroke
				(width 0.1524)
				(type default)
			)
			(layer "F.SilkS")
		)
		(fp_rect
			(start -0.508 0.9398)
			(end 0.508 -0.9398)
			(stroke
				(width 0)
				(type default)
			)
			(fill no)
			(layer "F.CrtYd")
		)
		(fp_rect
			(start -0.508 0.9398)
			(end 0.508 -0.9398)
			(stroke
				(width 0)
				(type default)
			)
			(fill no)
			(layer "F.Fab")
		)
		(pad "1" smd custom
			(at 0 -0.4445 90)
			(size 0.1397 0.1397)
			(layers "F.Cu" "F.Mask" "F.Paste")
			(net "DRV_ACT_NET7")
			(options
				(clearance outline)
				(anchor circle)
			)
			(primitives
				(gr_poly
					(pts
						(arc
							(start -0.1778 -0.2794)
							(mid -0.249642 -0.249642)
							(end -0.2794 -0.1778)
						)
						(arc
							(start -0.2794 0.1778)
							(mid -0.249642 0.249642)
							(end -0.1778 0.2794)
						)
						(arc
							(start 0.1778 0.2794)
							(mid 0.249642 0.249642)
							(end 0.2794 0.1778)
						)
						(arc
							(start 0.2794 -0.1778)
							(mid 0.249642 -0.249642)
							(end 0.1778 -0.2794)
						)
					)
					(width 0)
					(fill yes)
				)
			)
		)
		(pad "2" smd custom
			(at 0 0.4445 90)
			(size 0.1397 0.1397)
			(layers "F.Cu" "F.Mask" "F.Paste")
			(net "DRIVE_ACT_7")
			(options
				(clearance outline)
				(anchor circle)
			)
			(primitives
				(gr_poly
					(pts
						(arc
							(start -0.1778 -0.2794)
							(mid -0.249642 -0.249642)
							(end -0.2794 -0.1778)
						)
						(arc
							(start -0.2794 0.1778)
							(mid -0.249642 0.249642)
							(end -0.1778 0.2794)
						)
						(arc
							(start 0.1778 0.2794)
							(mid 0.249642 0.249642)
							(end 0.2794 0.1778)
						)
						(arc
							(start 0.2794 -0.1778)
							(mid 0.249642 -0.249642)
							(end 0.1778 -0.2794)
						)
					)
					(width 0)
					(fill yes)
				)
			)
		)
	)
)
